# T6G (Grand Teton) — schematic netlist excerpt (pin names and nets, part order shuffled) for the footprints in the layout excerpt that follows; sources: Cadence DE-HDL packaged netlist, KiCad conversion of 04192023_DAF0TMB3IC0_F0TG_MB_C_brd_V02_OCP.brd

R8057  Q_RES  33 5% CHIP  pkg 0402LF  page 200 : A = PWRGD_PVDDCR_CPU1_P0 ; B = PWRGD_PVDDCR_CPU1_P0_R

(kicad_pcb
	(version 20260206)
	(generator "pcbnew")
	(generator_version "10.0")
	(general
		(thickness 1.6)
		(legacy_teardrops no)
	)
	(paper "A4")
	(title_block
		(title "04192023_DAF0TMB3IC0_F0TG_MB_C_brd_V02_OCP.brd")
		(comment 1 "Grand Teton / footprints 4616-4616 of 8354")
	)
	(layers
		(0 "F.Cu" signal "TOP")
		(4 "In1.Cu" signal "GND")
		(6 "In2.Cu" signal "IN1")
		(8 "In3.Cu" signal "GND1")
		(10 "In4.Cu" signal "IN2")
		(12 "In5.Cu" signal "GND2")
		(14 "In6.Cu" signal "IN3")
		(16 "In7.Cu" signal "GND3")
		(18 "In8.Cu" signal "VCC")
		(20 "In9.Cu" signal "VCC1")
		(22 "In10.Cu" signal "GND4")
		(24 "In11.Cu" signal "IN4")
		(26 "In12.Cu" signal "GND5")
		(28 "In13.Cu" signal "IN5")
		(30 "In14.Cu" signal "GND6")
		(32 "In15.Cu" signal "IN6")
		(34 "In16.Cu" signal "GND7")
		(2 "B.Cu" signal "BOTTOM")
		(9 "F.Adhes" user "F.Adhesive")
		(11 "B.Adhes" user "B.Adhesive")
		(13 "F.Paste" user "Package Geometry/Pastemask Top")
		(15 "B.Paste" user "Package Geometry/Pastemask Bottom")
		(5 "F.SilkS" user "Ref Des/Silkscreen Top")
		(7 "B.SilkS" user "Ref Des/Silkscreen Bottom")
		(1 "F.Mask" user "Board Geometry/Soldermask Top")
		(3 "B.Mask" user "Board Geometry/Soldermask Bottom")
		(17 "Dwgs.User" user "User.Drawings")
		(19 "Cmts.User" user "User.Comments")
		(21 "Eco1.User" user "User.Eco1")
		(23 "Eco2.User" user "User.Eco2")
		(25 "Edge.Cuts" user "Board Geometry/Outline")
		(27 "Margin" user)
		(31 "F.CrtYd" user "Package Geometry/Place Bound Top")
		(29 "B.CrtYd" user "Package Geometry/Place Bound Bottom")
		(35 "F.Fab" user "Ref Des/Assembly Top")
		(33 "B.Fab" user "Ref Des/Assembly Bottom")
	)
	(footprint ""
		(layer "F.Cu")
		(at 302.1584 -363.982)
		(property "Reference" "R8057"
			(at 0 0 0)
			(layer "F.SilkS")
			(hide yes)
			(effects
				(font
					(size 1.27 1.27)
				)
			)
		)
		(property "Value" ""
			(at 0 0 0)
			(layer "F.Fab")
			(effects
				(font
					(size 1.27 1.27)
				)
			)
		)
		(duplicate_pad_numbers_are_jumpers no)
		(fp_line
			(start -0.7874 -0.4064)
			(end 0.7874 -0.4064)
			(stroke
				(width 0.1524)
				(type default)
			)
			(layer "F.SilkS")
		)
		(fp_line
			(start -0.7874 0.4064)
			(end -0.7874 -0.4064)
			(stroke
				(width 0.1524)
				(type default)
			)
			(layer "F.SilkS")
		)
		(fp_line
			(start 0.7874 -0.4064)
			(end 0.7874 0.4064)
			(stroke
				(width 0.1524)
				(type default)
			)
			(layer "F.SilkS")
		)
		(fp_line
			(start 0.7874 0.4064)
			(end -0.7874 0.4064)
			(stroke
				(width 0.1524)
				(type default)
			)
			(layer "F.SilkS")
		)
		(fp_line
			(start -0.67945 -0.305054)
			(end -0.12065 -0.305054)
			(stroke
				(width 0.1)
				(type default)
			)
			(layer "F.Fab")
		)
		(fp_line
			(start -0.67945 0.3048)
			(end -0.67945 -0.305054)
			(stroke
				(width 0.1)
				(type default)
			)
			(layer "F.Fab")
		)
		(fp_line
			(start -0.12065 -0.305054)
			(end -0.12065 -0.2794)
			(stroke
				(width 0.1)
				(type default)
			)
			(layer "F.Fab")
		)
		(fp_line
			(start -0.12065 -0.2794)
			(end 0.12065 -0.2794)
			(stroke
				(width 0.1)
				(type default)
			)
			(layer "F.Fab")
		)
		(fp_line
			(start -0.12065 0.2794)
			(end -0.12065 0.3048)
			(stroke
				(width 0.1)
				(type default)
			)
			(layer "F.Fab")
		)
		(fp_line
			(start -0.12065 0.3048)
			(end -0.67945 0.3048)
			(stroke
				(width 0.1)
				(type default)
			)
			(layer "F.Fab")
		)
		(fp_line
			(start 0.120396 0.2794)
			(end -0.12065 0.2794)
			(stroke
				(width 0.1)
				(type default)
			)
			(layer "F.Fab")
		)
		(fp_line
			(start 0.120396 0.3048)
			(end 0.120396 0.2794)
			(stroke
				(width 0.1)
				(type default)
			)
			(layer "F.Fab")
		)
		(fp_line
			(start 0.12065 -0.3048)
			(end 0.67945 -0.3048)
			(stroke
				(width 0.1)
				(type default)
			)
			(layer "F.Fab")
		)
		(fp_line
			(start 0.12065 -0.2794)
			(end 0.12065 -0.3048)
			(stroke
				(width 0.1)
				(type default)
			)
			(layer "F.Fab")
		)
		(fp_line
			(start 0.67945 -0.3048)
			(end 0.67945 0.3048)
			(stroke
				(width 0.1)
				(type default)
			)
			(layer "F.Fab")
		)
		(fp_line
			(start 0.67945 0.3048)
			(end 0.120396 0.3048)
			(stroke
				(width 0.1)
				(type default)
			)
			(layer "F.Fab")
		)
		(pad "1" smd circle
			(at -0.40005 0)
			(size 0 0)
			(layers "F.Cu" "F.Mask" "F.Paste")
			(net "PWRGD_PVDDCR_CPU1_P0")
		)
		(pad "2" smd circle
			(at 0.40005 0)
			(size 0 0)
			(layers "F.Cu" "F.Mask" "F.Paste")
			(net "PWRGD_PVDDCR_CPU1_P0_R")
		)
	)
)
